(kicad_pcb
	(version 20260206)
	(generator "pcbnew")
	(generator_version "10.0")
	(general
		(thickness 1.6)
		(legacy_teardrops no)
	)
	(paper "A4")
	(title_block
		(title "Bryce Canyon_F.DPB_16315-1-OCP.brd")
		(comment 1 "Bryce Canyon / footprints 1485-1490 of 2223")
	)
	(layers
		(0 "F.Cu" signal "TOP")
		(4 "In1.Cu" signal "L2GND")
		(6 "In2.Cu" signal "L3")
		(8 "In3.Cu" signal "L4GND")
		(10 "In4.Cu" signal "L5")
		(12 "In5.Cu" signal "L6VCC")
		(14 "In6.Cu" signal "L7VCC")
		(16 "In7.Cu" signal "L8")
		(18 "In8.Cu" signal "L9GND")
		(20 "In9.Cu" signal "L10")
		(22 "In10.Cu" signal "L11GND")
		(2 "B.Cu" signal "BOTTOM")
		(9 "F.Adhes" user "F.Adhesive")
		(11 "B.Adhes" user "B.Adhesive")
		(13 "F.Paste" user "Package Geometry/Pastemask Top")
		(15 "B.Paste" user "Package Geometry/Pastemask Bottom")
		(5 "F.SilkS" user "Ref Des/Silkscreen Top")
		(7 "B.SilkS" user "Ref Des/Silkscreen Bottom")
		(1 "F.Mask" user "Board Geometry/Soldermask Top")
		(3 "B.Mask" user "Board Geometry/Soldermask Bottom")
		(17 "Dwgs.User" user "User.Drawings")
		(19 "Cmts.User" user "User.Comments")
		(21 "Eco1.User" user "User.Eco1")
		(23 "Eco2.User" user "User.Eco2")
		(25 "Edge.Cuts" user "Board Geometry/Outline")
		(27 "Margin" user)
		(31 "F.CrtYd" user "Package Geometry/Place Bound Top")
		(29 "B.CrtYd" user "Package Geometry/Place Bound Bottom")
		(35 "F.Fab" user "Ref Des/Assembly Top")
		(33 "B.Fab" user "Ref Des/Assembly Bottom")
	)
	(footprint ""
		(layer "F.Cu")
		(at 458.3049 -42.585894)
		(property "Reference" "R924"
			(at 0 0 0)
			(layer "F.SilkS")
			(hide yes)
			(effects
				(font
					(size 1.27 1.27)
				)
			)
		)
		(property "Value" "4K7R2J-2-GP"
			(at 0.064008 -3.993896 0)
			(unlocked yes)
			(layer "F.Fab")
			(hide yes)
			(effects
				(font
					(size 1.016 1.016)
					(thickness 0.1524)
				)
			)
		)
		(property "Device Type" "R402H16"
			(at 0.064008 -5.517896 0)
			(unlocked yes)
			(layer "F.Fab")
			(hide yes)
			(effects
				(font
					(size 1.016 1.016)
					(thickness 0.1524)
				)
			)
		)
		(duplicate_pad_numbers_are_jumpers no)
		(fp_line
			(start -0.508 -0.9398)
			(end -0.508 0.9398)
			(stroke
				(width 0.1524)
				(type default)
			)
			(layer "F.SilkS")
		)
		(fp_line
			(start 0.508 -0.9398)
			(end -0.508 -0.9398)
			(stroke
				(width 0.1524)
				(type default)
			)
			(layer "F.SilkS")
		)
		(fp_rect
			(start -0.508 0.9398)
			(end 0.508 -0.9398)
			(stroke
				(width 0)
				(type default)
			)
			(fill no)
			(layer "F.CrtYd")
		)
		(fp_rect
			(start -0.508 0.9398)
			(end 0.508 -0.9398)
			(stroke
				(width 0)
				(type default)
			)
			(fill no)
			(layer "F.Fab")
		)
		(pad "1" smd custom
			(at 0 -0.4445)
			(size 0.1397 0.1397)
			(layers "F.Cu" "F.Mask" "F.Paste")
			(net "SW_PWR_R_HDD34")
			(options
				(clearance outline)
				(anchor circle)
			)
			(primitives
				(gr_poly
					(pts
						(arc
							(start -0.1778 -0.2794)
							(mid -0.249642 -0.249642)
							(end -0.2794 -0.1778)
						)
						(arc
							(start -0.2794 0.1778)
							(mid -0.249642 0.249642)
							(end -0.1778 0.2794)
						)
						(arc
							(start 0.1778 0.2794)
							(mid 0.249642 0.249642)
							(end 0.2794 0.1778)
						)
						(arc
							(start 0.2794 -0.1778)
							(mid 0.249642 -0.249642)
							(end 0.1778 -0.2794)
						)
					)
					(width 0)
					(fill yes)
				)
			)
		)
		(pad "2" smd custom
			(at 0 0.4445)
			(size 0.1397 0.1397)
			(layers "F.Cu" "F.Mask" "F.Paste")
			(net "GND")
			(options
				(clearance outline)
				(anchor circle)
			)
			(primitives
				(gr_poly
					(pts
						(arc
							(start -0.1778 -0.2794)
							(mid -0.249642 -0.249642)
							(end -0.2794 -0.1778)
						)
						(arc
							(start -0.2794 0.1778)
							(mid -0.249642 0.249642)
							(end -0.1778 0.2794)
						)
						(arc
							(start 0.1778 0.2794)
							(mid 0.249642 0.249642)
							(end 0.2794 0.1778)
						)
						(arc
							(start 0.2794 -0.1778)
							(mid 0.249642 -0.249642)
							(end 0.1778 -0.2794)
						)
					)
					(width 0)
					(fill yes)
				)
			)
		)
	)
	(footprint ""
		(layer "F.Cu")
		(at 246.207788 -385.310126 90)
		(property "Reference" "C583"
			(at 0 0 90)
			(layer "F.SilkS")
			(hide yes)
			(effects
				(font
					(size 1.27 1.27)
				)
			)
		)
		(property "Value" "SC1KP50V2KX-1GP"
			(at 1.1811 -2.7051 90)
			(unlocked yes)
			(layer "F.Fab")
			(hide yes)
			(effects
				(font
					(size 1.016 1.016)
					(thickness 0.1524)
				)
			)
		)
		(property "Device Type" "C402H22"
			(at 1.1811 -4.2291 90)
			(unlocked yes)
			(layer "F.Fab")
			(hide yes)
			(effects
				(font
					(size 1.016 1.016)
					(thickness 0.1524)
				)
			)
		)
		(duplicate_pad_numbers_are_jumpers no)
		(fp_rect
			(start -0.4318 0.9525)
			(end 0.4318 -0.9525)
			(stroke
				(width 0)
				(type default)
			)
			(fill no)
			(layer "F.CrtYd")
		)
		(fp_rect
			(start -0.4318 0.9525)
			(end 0.4318 -0.9525)
			(stroke
				(width 0)
				(type default)
			)
			(fill no)
			(layer "F.Fab")
		)
		(pad "1" smd custom
			(at 0 -0.4445 90)
			(size 0.1524 0.1524)
			(layers "F.Cu" "F.Mask" "F.Paste")
			(net "MB3_TEMP_B")
			(options
				(clearance outline)
				(anchor circle)
			)
			(primitives
				(gr_poly
					(pts
						(arc
							(start 0.3048 -0.2032)
							(mid 0.275042 -0.275042)
							(end 0.2032 -0.3048)
						)
						(arc
							(start -0.2032 -0.3048)
							(mid -0.275042 -0.275042)
							(end -0.3048 -0.2032)
						)
						(arc
							(start -0.3048 0.2032)
							(mid -0.275042 0.275042)
							(end -0.2032 0.3048)
						)
						(arc
							(start 0.2032 0.3048)
							(mid 0.275042 0.275042)
							(end 0.3048 0.2032)
						)
					)
					(width 0)
					(fill yes)
				)
			)
		)
		(pad "2" smd custom
			(at 0 0.4445 90)
			(size 0.1524 0.1524)
			(layers "F.Cu" "F.Mask" "F.Paste")
			(net "MB3_TEMP_E")
			(options
				(clearance outline)
				(anchor circle)
			)
			(primitives
				(gr_poly
					(pts
						(arc
							(start 0.3048 -0.2032)
							(mid 0.275042 -0.275042)
							(end 0.2032 -0.3048)
						)
						(arc
							(start -0.2032 -0.3048)
							(mid -0.275042 -0.275042)
							(end -0.3048 -0.2032)
						)
						(arc
							(start -0.3048 0.2032)
							(mid -0.275042 0.275042)
							(end -0.2032 0.3048)
						)
						(arc
							(start 0.2032 0.3048)
							(mid 0.275042 0.275042)
							(end 0.3048 0.2032)
						)
					)
					(width 0)
					(fill yes)
				)
			)
		)
	)
	(footprint ""
		(layer "F.Cu")
		(at 231.902 -254.635 180)
		(property "Reference" "U4"
			(at 0 0 180)
			(layer "F.SilkS")
			(hide yes)
			(effects
				(font
					(size 1.27 1.27)
				)
			)
		)
		(property "Value" "TCA9555PWR-GP"
			(at 0 -6.9342 180)
			(unlocked yes)
			(layer "F.Fab")
			(hide yes)
			(effects
				(font
					(size 1.016 1.016)
					(thickness 0.1524)
				)
			)
		)
		(property "Device Type" "TSOIC24H48"
			(at 0 -8.5852 180)
			(unlocked yes)
			(layer "F.Fab")
			(hide yes)
			(effects
				(font
					(size 1.016 1.016)
					(thickness 0.1524)
				)
			)
		)
		(duplicate_pad_numbers_are_jumpers no)
		(fp_line
			(start 3.81 1.397)
			(end -4.2291 1.397)
			(stroke
				(width 0.1524)
				(type default)
			)
			(layer "F.SilkS")
		)
		(fp_line
			(start 3.81 -1.397)
			(end 3.81 1.397)
			(stroke
				(width 0.1524)
				(type default)
			)
			(layer "F.SilkS")
		)
		(fp_line
			(start -3.429 0)
			(end -4.2291 0.8001)
			(stroke
				(width 0.1524)
				(type default)
			)
			(layer "F.SilkS")
		)
		(fp_line
			(start -4.22656 3.81)
			(end -4.2291 1.397)
			(stroke
				(width 0.508)
				(type default)
			)
			(layer "F.SilkS")
		)
		(fp_line
			(start -4.2291 3.937)
			(end -4.2291 -1.397)
			(stroke
				(width 0.1524)
				(type default)
			)
			(layer "F.SilkS")
		)
		(fp_line
			(start -4.2291 -0.8001)
			(end -3.429 0)
			(stroke
				(width 0.1524)
				(type default)
			)
			(layer "F.SilkS")
		)
		(fp_line
			(start -4.2291 -1.397)
			(end 3.81 -1.397)
			(stroke
				(width 0.1524)
				(type default)
			)
			(layer "F.SilkS")
		)
		(fp_poly
			(pts
				(xy -3.90652 -1.8542) (xy 3.90652 -1.8542) (xy 3.90652 1.8542) (xy -3.90652 1.8542)
			)
			(stroke
				(width 0)
				(type default)
			)
			(fill yes)
			(layer "F.SilkS")
		)
		(fp_poly
			(pts
				(xy -4.2164 3.81) (xy 4.2164 3.81) (xy 4.22656 -3.81) (xy -4.2164 -3.81)
			)
			(stroke
				(width 0)
				(type default)
			)
			(fill no)
			(layer "F.CrtYd")
		)
		(fp_poly
			(pts
				(xy -4.22656 -3.81) (xy 4.22656 -3.81) (xy 4.22656 3.81) (xy -4.22656 3.81)
			)
			(stroke
				(width 0)
				(type default)
			)
			(fill no)
			(layer "F.Fab")
		)
		(pad "1" smd rect
			(at -3.57632 2.8194 180)
			(size 0.3556 1.524)
			(layers "F.Cu" "F.Mask" "F.Paste")
			(net "IO_EXP4_INT_N")
		)
		(pad "2" smd rect
			(at -2.92608 2.8194 180)
			(size 0.3556 1.524)
			(layers "F.Cu" "F.Mask" "F.Paste")
			(net "IO_EXP4_A1")
		)
		(pad "3" smd rect
			(at -2.27584 2.8194 180)
			(size 0.3556 1.524)
			(layers "F.Cu" "F.Mask" "F.Paste")
			(net "IO_EXP4_A2")
		)
		(pad "4" smd rect
			(at -1.6256 2.8194 180)
			(size 0.3556 1.524)
			(layers "F.Cu" "F.Mask" "F.Paste")
			(net "DRIVE_A_0_INS")
		)
		(pad "5" smd rect
			(at -0.97536 2.8194 180)
			(size 0.3556 1.524)
			(layers "F.Cu" "F.Mask" "F.Paste")
			(net "DRIVE_A_1_INS")
		)
		(pad "6" smd rect
			(at -0.32512 2.8194 180)
			(size 0.3556 1.524)
			(layers "F.Cu" "F.Mask" "F.Paste")
			(net "DRIVE_A_2_INS")
		)
		(pad "7" smd rect
			(at 0.32512 2.8194 180)
			(size 0.3556 1.524)
			(layers "F.Cu" "F.Mask" "F.Paste")
			(net "DRIVE_A_3_INS")
		)
		(pad "8" smd rect
			(at 0.97536 2.8194 180)
			(size 0.3556 1.524)
			(layers "F.Cu" "F.Mask" "F.Paste")
			(net "DRIVE_A_4_INS")
		)
		(pad "9" smd rect
			(at 1.6256 2.8194 180)
			(size 0.3556 1.524)
			(layers "F.Cu" "F.Mask" "F.Paste")
			(net "DRIVE_A_5_INS")
		)
		(pad "10" smd rect
			(at 2.27584 2.8194 180)
			(size 0.3556 1.524)
			(layers "F.Cu" "F.Mask" "F.Paste")
			(net "DRIVE_A_6_INS")
		)
		(pad "11" smd rect
			(at 2.92608 2.8194 180)
			(size 0.3556 1.524)
			(layers "F.Cu" "F.Mask" "F.Paste")
			(net "DRIVE_A_7_INS")
		)
		(pad "12" smd rect
			(at 3.57632 2.8194 180)
			(size 0.3556 1.524)
			(layers "F.Cu" "F.Mask" "F.Paste")
			(net "GND")
		)
		(pad "13" smd rect
			(at 3.57632 -2.8194 180)
			(size 0.3556 1.524)
			(layers "F.Cu" "F.Mask" "F.Paste")
			(net "DRIVE_A_8_INS")
		)
		(pad "14" smd rect
			(at 2.92608 -2.8194 180)
			(size 0.3556 1.524)
			(layers "F.Cu" "F.Mask" "F.Paste")
			(net "DRIVE_A_9_INS")
		)
		(pad "15" smd rect
			(at 2.27584 -2.8194 180)
			(size 0.3556 1.524)
			(layers "F.Cu" "F.Mask" "F.Paste")
			(net "DRIVE_A_10_INS")
		)
		(pad "16" smd rect
			(at 1.6256 -2.8194 180)
			(size 0.3556 1.524)
			(layers "F.Cu" "F.Mask" "F.Paste")
			(net "DRIVE_A_11_INS")
		)
		(pad "17" smd rect
			(at 0.97536 -2.8194 180)
			(size 0.3556 1.524)
			(layers "F.Cu" "F.Mask" "F.Paste")
			(net "DRIVE_A_12_INS")
		)
		(pad "18" smd rect
			(at 0.32512 -2.8194 180)
			(size 0.3556 1.524)
			(layers "F.Cu" "F.Mask" "F.Paste")
			(net "DRIVE_A_13_INS")
		)
		(pad "19" smd rect
			(at -0.32512 -2.8194 180)
			(size 0.3556 1.524)
			(layers "F.Cu" "F.Mask" "F.Paste")
			(net "DRIVE_A_14_INS")
		)
		(pad "20" smd rect
			(at -0.97536 -2.8194 180)
			(size 0.3556 1.524)
			(layers "F.Cu" "F.Mask" "F.Paste")
			(net "DRIVE_A_15_INS")
		)
		(pad "21" smd rect
			(at -1.6256 -2.8194 180)
			(size 0.3556 1.524)
			(layers "F.Cu" "F.Mask" "F.Paste")
			(net "IO_EXP4_A0")
		)
		(pad "22" smd rect
			(at -2.27584 -2.8194 180)
			(size 0.3556 1.524)
			(layers "F.Cu" "F.Mask" "F.Paste")
			(net "IO_EXP4_SCL")
		)
		(pad "23" smd rect
			(at -2.92608 -2.8194 180)
			(size 0.3556 1.524)
			(layers "F.Cu" "F.Mask" "F.Paste")
			(net "IO_EXP4_SDA")
		)
		(pad "24" smd rect
			(at -3.57632 -2.8194 180)
			(size 0.3556 1.524)
			(layers "F.Cu" "F.Mask" "F.Paste")
			(net "P3V3_STBY_A")
		)
	)
	(footprint ""
		(layer "F.Cu")
		(at 133.313424 -127.78867 180)
		(property "Reference" "Q243"
			(at 0 0 180)
			(layer "F.SilkS")
			(hide yes)
			(effects
				(font
					(size 1.27 1.27)
				)
			)
		)
		(property "Value" "2N7002K-2-GP"
			(at 0.127 -8.9662 180)
			(unlocked yes)
			(layer "F.Fab")
			(hide yes)
			(effects
				(font
					(size 1.016 1.016)
					(thickness 0.1524)
				)
			)
		)
		(property "Device Type" "SOT23DGS2D4H44"
			(at 0.127 -10.4902 180)
			(unlocked yes)
			(layer "F.Fab")
			(hide yes)
			(effects
				(font
					(size 1.016 1.016)
					(thickness 0.1524)
				)
			)
		)
		(duplicate_pad_numbers_are_jumpers no)
		(fp_line
			(start 1.651 1.778)
			(end 1.651 -1.778)
			(stroke
				(width 0.1524)
				(type default)
			)
			(layer "F.SilkS")
		)
		(fp_line
			(start 1.651 -1.778)
			(end -1.651 -1.778)
			(stroke
				(width 0.1524)
				(type default)
			)
			(layer "F.SilkS")
		)
		(fp_line
			(start -1.651 1.778)
			(end 1.651 1.778)
			(stroke
				(width 0.1524)
				(type default)
			)
			(layer "F.SilkS")
		)
		(fp_line
			(start -1.651 -1.778)
			(end -1.651 1.778)
			(stroke
				(width 0.1524)
				(type default)
			)
			(layer "F.SilkS")
		)
		(fp_poly
			(pts
				(xy -1.778 1.8796) (xy -1.778 -1.8796) (xy 1.778 -1.8796) (xy 1.778 1.8796)
			)
			(stroke
				(width 0)
				(type default)
			)
			(fill no)
			(layer "F.CrtYd")
		)
		(fp_poly
			(pts
				(xy -1.778 1.8796) (xy -1.778 -1.8796) (xy 1.778 -1.8796) (xy 1.778 1.8796)
			)
			(stroke
				(width 0)
				(type default)
			)
			(fill no)
			(layer "F.Fab")
		)
		(pad "D" smd custom
			(at 0 -0.9525 180)
			(size 0.1905 0.1905)
			(layers "F.Cu" "F.Mask" "F.Paste")
			(net "FLT_HDD16_N")
			(options
				(clearance outline)
				(anchor circle)
			)
			(primitives
				(gr_poly
					(pts
						(arc
							(start -0.1778 0.5715)
							(mid -0.321484 0.511984)
							(end -0.381 0.3683)
						)
						(arc
							(start -0.381 -0.3683)
							(mid -0.321484 -0.511984)
							(end -0.1778 -0.5715)
						)
						(arc
							(start 0.1778 -0.5715)
							(mid 0.321484 -0.511984)
							(end 0.381 -0.3683)
						)
						(arc
							(start 0.381 0.3683)
							(mid 0.321484 0.511984)
							(end 0.1778 0.5715)
						)
					)
					(width 0)
					(fill yes)
				)
			)
		)
		(pad "G" smd custom
			(at -0.98425 0.9525 180)
			(size 0.1905 0.1905)
			(layers "F.Cu" "F.Mask" "F.Paste")
			(net "DRIVE_A_16_FLT_LED")
			(options
				(clearance outline)
				(anchor circle)
			)
			(primitives
				(gr_poly
					(pts
						(arc
							(start -0.1778 0.5715)
							(mid -0.321484 0.511984)
							(end -0.381 0.3683)
						)
						(arc
							(start -0.381 -0.3683)
							(mid -0.321484 -0.511984)
							(end -0.1778 -0.5715)
						)
						(arc
							(start 0.1778 -0.5715)
							(mid 0.321484 -0.511984)
							(end 0.381 -0.3683)
						)
						(arc
							(start 0.381 0.3683)
							(mid 0.321484 0.511984)
							(end 0.1778 0.5715)
						)
					)
					(width 0)
					(fill yes)
				)
			)
		)
		(pad "S" smd custom
			(at 0.98425 0.9525 180)
			(size 0.1905 0.1905)
			(layers "F.Cu" "F.Mask" "F.Paste")
			(net "GND")
			(options
				(clearance outline)
				(anchor circle)
			)
			(primitives
				(gr_poly
					(pts
						(arc
							(start -0.1778 0.5715)
							(mid -0.321484 0.511984)
							(end -0.381 0.3683)
						)
						(arc
							(start -0.381 -0.3683)
							(mid -0.321484 -0.511984)
							(end -0.1778 -0.5715)
						)
						(arc
							(start 0.1778 -0.5715)
							(mid 0.321484 -0.511984)
							(end 0.381 -0.3683)
						)
						(arc
							(start 0.381 0.3683)
							(mid 0.321484 0.511984)
							(end 0.1778 0.5715)
						)
					)
					(width 0)
					(fill yes)
				)
			)
		)
	)
	(footprint ""
		(layer "F.Cu")
		(at 364.290102 -48.554894 -90)
		(property "Reference" "R850"
			(at 0 0 270)
			(layer "F.SilkS")
			(hide yes)
			(effects
				(font
					(size 1.27 1.27)
				)
			)
		)
		(property "Value" "4K7R2J-2-GP"
			(at 0.064008 -3.993896 270)
			(unlocked yes)
			(layer "F.Fab")
			(hide yes)
			(effects
				(font
					(size 1.016 1.016)
					(thickness 0.1524)
				)
			)
		)
		(property "Device Type" "R402H16"
			(at 0.064008 -5.517896 270)
			(unlocked yes)
			(layer "F.Fab")
			(hide yes)
			(effects
				(font
					(size 1.016 1.016)
					(thickness 0.1524)
				)
			)
		)
		(duplicate_pad_numbers_are_jumpers no)
		(fp_line
			(start -0.508 -0.9398)
			(end -0.508 0.9398)
			(stroke
				(width 0.1524)
				(type default)
			)
			(layer "F.SilkS")
		)
		(fp_line
			(start 0.508 -0.9398)
			(end -0.508 -0.9398)
			(stroke
				(width 0.1524)
				(type default)
			)
			(layer "F.SilkS")
		)
		(fp_rect
			(start -0.508 0.9398)
			(end 0.508 -0.9398)
			(stroke
				(width 0)
				(type default)
			)
			(fill no)
			(layer "F.CrtYd")
		)
		(fp_rect
			(start -0.508 0.9398)
			(end 0.508 -0.9398)
			(stroke
				(width 0)
				(type default)
			)
			(fill no)
			(layer "F.Fab")
		)
		(pad "1" smd custom
			(at 0 -0.4445 270)
			(size 0.1397 0.1397)
			(layers "F.Cu" "F.Mask" "F.Paste")
			(net "P12V_A")
			(options
				(clearance outline)
				(anchor circle)
			)
			(primitives
				(gr_poly
					(pts
						(arc
							(start -0.1778 -0.2794)
							(mid -0.249642 -0.249642)
							(end -0.2794 -0.1778)
						)
						(arc
							(start -0.2794 0.1778)
							(mid -0.249642 0.249642)
							(end -0.1778 0.2794)
						)
						(arc
							(start 0.1778 0.2794)
							(mid 0.249642 0.249642)
							(end 0.2794 0.1778)
						)
						(arc
							(start 0.2794 -0.1778)
							(mid 0.249642 -0.249642)
							(end 0.1778 -0.2794)
						)
					)
					(width 0)
					(fill yes)
				)
			)
		)
		(pad "2" smd custom
			(at 0 0.4445 270)
			(size 0.1397 0.1397)
			(layers "F.Cu" "F.Mask" "F.Paste")
			(net "SW_HDD_P31")
			(options
				(clearance outline)
				(anchor circle)
			)
			(primitives
				(gr_poly
					(pts
						(arc
							(start -0.1778 -0.2794)
							(mid -0.249642 -0.249642)
							(end -0.2794 -0.1778)
						)
						(arc
							(start -0.2794 0.1778)
							(mid -0.249642 0.249642)
							(end -0.1778 0.2794)
						)
						(arc
							(start 0.1778 0.2794)
							(mid 0.249642 0.249642)
							(end 0.2794 0.1778)
						)
						(arc
							(start 0.2794 -0.1778)
							(mid 0.249642 -0.249642)
							(end 0.1778 -0.2794)
						)
					)
					(width 0)
					(fill yes)
				)
			)
		)
	)
	(footprint ""
		(layer "F.Cu")
		(at 384.631438 -139.448794)
		(property "Reference" "D43"
			(at 0 0 0)
			(layer "F.SilkS")
			(hide yes)
			(effects
				(font
					(size 1.27 1.27)
				)
			)
		)
		(property "Value" "MMPZ5228BPT-GP"
			(at 0 -6.7818 0)
			(unlocked yes)
			(layer "F.Fab")
			(hide yes)
			(effects
				(font
					(size 1.016 1.016)
					(thickness 0.1524)
				)
			)
		)
		(property "Device Type" "SOD323AKH40"
			(at 0 -8.6868 0)
			(unlocked yes)
			(layer "F.Fab")
			(hide yes)
			(effects
				(font
					(size 1.016 1.016)
					(thickness 0.1524)
				)
			)
		)
		(duplicate_pad_numbers_are_jumpers no)
		(fp_line
			(start -0.889 -1.9304)
			(end 0.889 -1.9304)
			(stroke
				(width 0.1524)
				(type default)
			)
			(layer "F.SilkS")
		)
		(fp_line
			(start -0.889 2.159)
			(end -0.889 -1.9304)
			(stroke
				(width 0.1524)
				(type default)
			)
			(layer "F.SilkS")
		)
		(fp_line
			(start 0.762 2.0574)
			(end -0.762 2.0574)
			(stroke
				(width 0.508)
				(type default)
			)
			(layer "F.SilkS")
		)
		(fp_line
			(start 0.889 -1.9304)
			(end 0.889 2.159)
			(stroke
				(width 0.1524)
				(type default)
			)
			(layer "F.SilkS")
		)
		(fp_line
			(start 0.889 2.159)
			(end -0.889 2.159)
			(stroke
				(width 0.1524)
				(type default)
			)
			(layer "F.SilkS")
		)
		(fp_rect
			(start -1.016 2.3114)
			(end 1.016 -2.0066)
			(stroke
				(width 0)
				(type default)
			)
			(fill no)
			(layer "F.CrtYd")
		)
		(fp_poly
			(pts
				(xy -1.016 -2.0066) (xy 1.016 -2.0066) (xy 1.016 2.3114) (xy -1.016 2.3114)
			)
			(stroke
				(width 0)
				(type default)
			)
			(fill no)
			(layer "F.Fab")
		)
		(pad "A" smd rect
			(at 0 -1.143)
			(size 0.5588 1.016)
			(layers "F.Cu" "F.Mask" "F.Paste")
			(net "GND")
		)
		(pad "K" smd rect
			(at 0 1.143)
			(size 0.5588 1.016)
			(layers "F.Cu" "F.Mask" "F.Paste")
			(net "VCCP_B")
		)
	)
)
